# TIMECARD (Time Appliance Project (Time Card)) — schematic netlist excerpt (pin names and nets, part order shuffled) for the footprints in the layout excerpt that follows; sources: Cadence DE-HDL packaged netlist, KiCad conversion of R4006-B0001-02_R01.brd

R123  RESISTOR  49.9OHM 1%  pkg SMC_0402R_H016  page 23 : \1\ = BF_SMA4_SIG_IO_CONN ; \2\ = SMA4_SIG_IO_CONN
R224  RESISTOR  1KOHM 1%  pkg SMC_0402R_H016  page 11 : \1\ = SG ; \2\ = PUDC

(kicad_pcb
	(version 20260206)
	(generator "pcbnew")
	(generator_version "10.0")
	(general
		(thickness 1.6)
		(legacy_teardrops no)
	)
	(paper "A4")
	(title_block
		(title "timecard-production-celestica-r4006 — R4006-B0001-02_R01.brd")
		(comment 1 "Time Appliance Project (Time Card) / footprints 964-965 of 1113")
	)
	(layers
		(0 "F.Cu" signal "TOP")
		(4 "In1.Cu" signal "L02_GND1")
		(6 "In2.Cu" signal "L03_SIG1")
		(8 "In3.Cu" signal "L04_GND2")
		(10 "In4.Cu" signal "L05_VCC1")
		(12 "In5.Cu" signal "L06_VCC2")
		(14 "In6.Cu" signal "L07_GND3")
		(16 "In7.Cu" signal "L08_SIG2")
		(18 "In8.Cu" signal "L09_GND4")
		(2 "B.Cu" signal "BOTTOM")
		(9 "F.Adhes" user "F.Adhesive")
		(11 "B.Adhes" user "B.Adhesive")
		(13 "F.Paste" user "Package Geometry/Pastemask Top")
		(15 "B.Paste" user "Package Geometry/Pastemask Bottom")
		(5 "F.SilkS" user "Ref Des/Silkscreen Top")
		(7 "B.SilkS" user "Ref Des/Silkscreen Bottom")
		(1 "F.Mask" user "Board Geometry/Soldermask Top")
		(3 "B.Mask" user "Board Geometry/Soldermask Bottom")
		(17 "Dwgs.User" user "User.Drawings")
		(19 "Cmts.User" user "User.Comments")
		(21 "Eco1.User" user "User.Eco1")
		(23 "Eco2.User" user "User.Eco2")
		(25 "Edge.Cuts" user "Board Geometry/Outline")
		(27 "Margin" user)
		(31 "F.CrtYd" user "Package Geometry/Place Bound Top")
		(29 "B.CrtYd" user "Package Geometry/Place Bound Bottom")
		(35 "F.Fab" user "Ref Des/Assembly Top")
		(33 "B.Fab" user "Ref Des/Assembly Bottom")
	)
	(footprint ""
		(layer "B.Cu")
		(at 117.348 -61.976 90)
		(property "Reference" "R224"
			(at 3.429 0.08763 270)
			(unlocked yes)
			(layer "B.SilkS")
			(effects
				(font
					(size 0.7874 0.5842)
					(thickness 0.1524)
				)
				(justify mirror)
			)
		)
		(property "Value" "VAL*"
			(at -0.02032 2.13233 90)
			(unlocked yes)
			(layer "B.Fab")
			(hide yes)
			(effects
				(font
					(size 0.7874 0.5842)
					(thickness 0.1524)
				)
				(justify mirror)
			)
		)
		(property "Device Type" "RESISTOR-G155-11001-01,1KOHM,1%"
			(at -0.008382 1.210564 90)
			(unlocked yes)
			(layer "B.Fab")
			(hide yes)
			(effects
				(font
					(size 0.7874 0.5842)
					(thickness 0.1524)
				)
				(justify mirror)
			)
		)
		(property "User Part Number" "PARTNUM*"
			(at -0.02032 4.024884 90)
			(unlocked yes)
			(layer "Cmts.User")
			(hide yes)
			(effects
				(font
					(size 0.7874 0.5842)
					(thickness 0.1524)
				)
				(justify mirror)
			)
		)
		(property "Tolerance" "TOL*"
			(at -0.044704 3.05435 90)
			(unlocked yes)
			(layer "Cmts.User")
			(hide yes)
			(effects
				(font
					(size 0.7874 0.5842)
					(thickness 0.1524)
				)
				(justify mirror)
			)
		)
		(duplicate_pad_numbers_are_jumpers no)
		(fp_line
			(start 1.143 -0.5588)
			(end 1.143 0.5588)
			(stroke
				(width 0.1)
				(type default)
			)
			(layer "B.SilkS")
		)
		(fp_line
			(start -1.143 -0.5588)
			(end 1.143 -0.5588)
			(stroke
				(width 0.1)
				(type default)
			)
			(layer "B.SilkS")
		)
		(fp_line
			(start 1.143 0.5588)
			(end -1.143 0.5588)
			(stroke
				(width 0.1)
				(type default)
			)
			(layer "B.SilkS")
		)
		(fp_line
			(start -1.143 0.5588)
			(end -1.143 -0.5588)
			(stroke
				(width 0.1)
				(type default)
			)
			(layer "B.SilkS")
		)
		(fp_rect
			(start -1.143 -0.5588)
			(end 1.143 0.5588)
			(stroke
				(width 0)
				(type default)
			)
			(fill no)
			(layer "B.CrtYd")
		)
		(fp_line
			(start 0.508 -0.3048)
			(end 0.508 0.3048)
			(stroke
				(width 0.1)
				(type default)
			)
			(layer "B.Fab")
		)
		(fp_line
			(start -0.508 -0.3048)
			(end 0.508 -0.3048)
			(stroke
				(width 0.1)
				(type default)
			)
			(layer "B.Fab")
		)
		(fp_line
			(start 0.508 0.3048)
			(end -0.508 0.3048)
			(stroke
				(width 0.1)
				(type default)
			)
			(layer "B.Fab")
		)
		(fp_line
			(start -0.508 0.3048)
			(end -0.508 -0.3048)
			(stroke
				(width 0.1)
				(type default)
			)
			(layer "B.Fab")
		)
		(pad "1" smd rect
			(at 0.5334 0 270)
			(size 0.7112 0.6096)
			(layers "B.Cu" "B.Mask" "B.Paste")
			(net "SG")
		)
		(pad "2" smd rect
			(at -0.5334 0 270)
			(size 0.7112 0.6096)
			(layers "B.Cu" "B.Mask" "B.Paste")
			(net "PUDC")
		)
		(zone
			(layer "B.Cu")
			(hatch none 0.5)
			(connect_pads
				(clearance 0)
			)
			(min_thickness 0.25)
			(keepout
				(tracks allowed)
				(vias not_allowed)
				(pads allowed)
				(copperpour not_allowed)
				(footprints allowed)
			)
			(placement
				(enabled no)
				(sheetname "")
			)
			(fill
				(thermal_gap 0.5)
				(thermal_bridge_width 0.5)
				(island_removal_mode 0)
			)
			(polygon
				(pts
					(xy 117.0432 -61.8998) (xy 117.6528 -61.8998) (xy 117.6528 -62.0522) (xy 117.0432 -62.0522)
				)
			)
		)
	)
	(footprint ""
		(layer "B.Cu")
		(at 13.462 -17.1704 -90)
		(property "Reference" "R123"
			(at -2.2606 -0.22225 270)
			(unlocked yes)
			(layer "B.SilkS")
			(effects
				(font
					(size 0.635 0.4064)
					(thickness 0.1524)
				)
				(justify mirror)
			)
		)
		(property "Value" "VAL*"
			(at -0.02032 2.13233 270)
			(unlocked yes)
			(layer "B.Fab")
			(hide yes)
			(effects
				(font
					(size 0.7874 0.5842)
					(thickness 0.1524)
				)
				(justify mirror)
			)
		)
		(property "Tolerance" "TOL*"
			(at -0.044704 3.05435 270)
			(unlocked yes)
			(layer "Cmts.User")
			(hide yes)
			(effects
				(font
					(size 0.7874 0.5842)
					(thickness 0.1524)
				)
				(justify mirror)
			)
		)
		(property "User Part Number" "PARTNUM*"
			(at -0.02032 4.024884 270)
			(unlocked yes)
			(layer "Cmts.User")
			(hide yes)
			(effects
				(font
					(size 0.7874 0.5842)
					(thickness 0.1524)
				)
				(justify mirror)
			)
		)
		(property "Device Type" "RESISTOR-G155-149R9-01,49.9OHMA"
			(at -0.008382 1.210564 270)
			(unlocked yes)
			(layer "B.Fab")
			(hide yes)
			(effects
				(font
					(size 0.7874 0.5842)
					(thickness 0.1524)
				)
				(justify mirror)
			)
		)
		(duplicate_pad_numbers_are_jumpers no)
		(fp_line
			(start -1.143 0.5588)
			(end -1.143 -0.5588)
			(stroke
				(width 0.1)
				(type default)
			)
			(layer "B.SilkS")
		)
		(fp_line
			(start 1.143 0.5588)
			(end -1.143 0.5588)
			(stroke
				(width 0.1)
				(type default)
			)
			(layer "B.SilkS")
		)
		(fp_line
			(start -1.143 -0.5588)
			(end 1.143 -0.5588)
			(stroke
				(width 0.1)
				(type default)
			)
			(layer "B.SilkS")
		)
		(fp_line
			(start 1.143 -0.5588)
			(end 1.143 0.5588)
			(stroke
				(width 0.1)
				(type default)
			)
			(layer "B.SilkS")
		)
		(fp_poly
			(pts
				(xy 1.143 0.5588) (xy -1.143 0.5588) (xy -1.143 -0.5588) (xy 1.143 -0.5588)
			)
			(stroke
				(width 0)
				(type default)
			)
			(fill no)
			(layer "B.CrtYd")
		)
		(fp_line
			(start -0.508 0.3048)
			(end -0.508 -0.3048)
			(stroke
				(width 0.1)
				(type default)
			)
			(layer "B.Fab")
		)
		(fp_line
			(start 0.508 0.3048)
			(end -0.508 0.3048)
			(stroke
				(width 0.1)
				(type default)
			)
			(layer "B.Fab")
		)
		(fp_line
			(start -0.508 -0.3048)
			(end 0.508 -0.3048)
			(stroke
				(width 0.1)
				(type default)
			)
			(layer "B.Fab")
		)
		(fp_line
			(start 0.508 -0.3048)
			(end 0.508 0.3048)
			(stroke
				(width 0.1)
				(type default)
			)
			(layer "B.Fab")
		)
		(pad "1" smd rect
			(at 0.5334 0 90)
			(size 0.7112 0.6096)
			(layers "B.Cu" "B.Mask" "B.Paste")
			(net "BF_SMA4_SIG_IO_CONN")
		)
		(pad "2" smd rect
			(at -0.5334 0 90)
			(size 0.7112 0.6096)
			(layers "B.Cu" "B.Mask" "B.Paste")
			(net "SMA4_SIG_IO_CONN")
		)
		(zone
			(layer "B.Cu")
			(hatch none 0.5)
			(connect_pads
				(clearance 0)
			)
			(min_thickness 0.25)
			(keepout
				(tracks allowed)
				(vias not_allowed)
				(pads allowed)
				(copperpour not_allowed)
				(footprints allowed)
			)
			(placement
				(enabled no)
				(sheetname "")
			)
			(fill
				(thermal_gap 0.5)
				(thermal_bridge_width 0.5)
				(island_removal_mode 0)
			)
			(polygon
				(pts
					(xy 13.1572 -17.0942) (xy 13.7668 -17.0942) (xy 13.7668 -17.2466) (xy 13.1572 -17.2466)
				)
			)
		)
		(zone
			(layer "B.Cu")
			(hatch none 0.5)
			(connect_pads
				(clearance 0)
			)
			(min_thickness 0.25)
			(keepout
				(tracks not_allowed)
				(vias allowed)
				(pads allowed)
				(copperpour not_allowed)
				(footprints allowed)
			)
			(placement
				(enabled no)
				(sheetname "")
			)
			(fill
				(thermal_gap 0.5)
				(thermal_bridge_width 0.5)
				(island_removal_mode 0)
			)
			(polygon
				(pts
					(xy 13.1572 -17.0942) (xy 13.7668 -17.0942) (xy 13.7668 -17.2466) (xy 13.1572 -17.2466)
				)
			)
		)
	)
)
